# S9S_MB_2U (Grand Teton) — schematic netlist excerpt (pin names and nets, part order shuffled) for the footprints in the layout excerpt that follows; sources: Cadence DE-HDL packaged netlist, KiCad conversion of 03242023_DA0F0TMBIJ0_F0T_Motherboard_J_brd_V01_OCP.brd

C3275  Q_CAP  1000PF 50V 5% X7R  pkg 0402  page 274 : A = PVCCFA_EHV_CPU0_EN_R ; B = GND
R2559  Q_RES  150 1% CHIP  pkg 0402LF  page 292 : A = SVID_CLK0_CPU1_R ; B = SVID_CLK_PVCCINFAON_CPU1_R

(kicad_pcb
	(version 20260206)
	(generator "pcbnew")
	(generator_version "10.0")
	(general
		(thickness 1.6)
		(legacy_teardrops no)
	)
	(paper "A4")
	(title_block
		(title "03242023_DA0F0TMBIJ0_F0T_Motherboard_J_brd_V01_OCP.brd")
		(comment 1 "Grand Teton / footprints 714-715 of 6105")
	)
	(layers
		(0 "F.Cu" signal "TOP")
		(4 "In1.Cu" signal "GND")
		(6 "In2.Cu" signal "IN1")
		(8 "In3.Cu" signal "GND1")
		(10 "In4.Cu" signal "IN2")
		(12 "In5.Cu" signal "GND2")
		(14 "In6.Cu" signal "IN3")
		(16 "In7.Cu" signal "GND3")
		(18 "In8.Cu" signal "VCC")
		(20 "In9.Cu" signal "VCC1")
		(22 "In10.Cu" signal "GND4")
		(24 "In11.Cu" signal "IN4")
		(26 "In12.Cu" signal "GND5")
		(28 "In13.Cu" signal "IN5")
		(30 "In14.Cu" signal "GND6")
		(32 "In15.Cu" signal "IN6")
		(34 "In16.Cu" signal "GND7")
		(2 "B.Cu" signal "BOTTOM")
		(9 "F.Adhes" user "F.Adhesive")
		(11 "B.Adhes" user "B.Adhesive")
		(13 "F.Paste" user "Package Geometry/Pastemask Top")
		(15 "B.Paste" user "Package Geometry/Pastemask Bottom")
		(5 "F.SilkS" user "Ref Des/Silkscreen Top")
		(7 "B.SilkS" user "Ref Des/Silkscreen Bottom")
		(1 "F.Mask" user "Board Geometry/Soldermask Top")
		(3 "B.Mask" user "Board Geometry/Soldermask Bottom")
		(17 "Dwgs.User" user "User.Drawings")
		(19 "Cmts.User" user "User.Comments")
		(21 "Eco1.User" user "User.Eco1")
		(23 "Eco2.User" user "User.Eco2")
		(25 "Edge.Cuts" user "Board Geometry/Outline")
		(27 "Margin" user)
		(31 "F.CrtYd" user "Package Geometry/Place Bound Top")
		(29 "B.CrtYd" user "Package Geometry/Place Bound Bottom")
		(35 "F.Fab" user "Ref Des/Assembly Top")
		(33 "B.Fab" user "Ref Des/Assembly Bottom")
	)
	(footprint ""
		(layer "F.Cu")
		(at 36.956238 -129.74574 180)
		(property "Reference" "R2559"
			(at 0 0 180)
			(layer "F.SilkS")
			(hide yes)
			(effects
				(font
					(size 1.27 1.27)
				)
			)
		)
		(property "Value" ""
			(at 0 0 180)
			(layer "F.Fab")
			(effects
				(font
					(size 1.27 1.27)
				)
			)
		)
		(duplicate_pad_numbers_are_jumpers no)
		(fp_line
			(start 0.7874 0.4064)
			(end -0.7874 0.4064)
			(stroke
				(width 0.1524)
				(type default)
			)
			(layer "F.SilkS")
		)
		(fp_line
			(start 0.7874 -0.4064)
			(end 0.7874 0.4064)
			(stroke
				(width 0.1524)
				(type default)
			)
			(layer "F.SilkS")
		)
		(fp_line
			(start -0.7874 0.4064)
			(end -0.7874 -0.4064)
			(stroke
				(width 0.1524)
				(type default)
			)
			(layer "F.SilkS")
		)
		(fp_line
			(start -0.7874 -0.4064)
			(end 0.7874 -0.4064)
			(stroke
				(width 0.1524)
				(type default)
			)
			(layer "F.SilkS")
		)
		(fp_line
			(start 0.67945 0.3048)
			(end 0.120396 0.3048)
			(stroke
				(width 0.1)
				(type default)
			)
			(layer "F.Fab")
		)
		(fp_line
			(start 0.67945 -0.3048)
			(end 0.67945 0.3048)
			(stroke
				(width 0.1)
				(type default)
			)
			(layer "F.Fab")
		)
		(fp_line
			(start 0.12065 -0.2794)
			(end 0.12065 -0.3048)
			(stroke
				(width 0.1)
				(type default)
			)
			(layer "F.Fab")
		)
		(fp_line
			(start 0.12065 -0.3048)
			(end 0.67945 -0.3048)
			(stroke
				(width 0.1)
				(type default)
			)
			(layer "F.Fab")
		)
		(fp_line
			(start 0.120396 0.3048)
			(end 0.120396 0.2794)
			(stroke
				(width 0.1)
				(type default)
			)
			(layer "F.Fab")
		)
		(fp_line
			(start 0.120396 0.2794)
			(end -0.12065 0.2794)
			(stroke
				(width 0.1)
				(type default)
			)
			(layer "F.Fab")
		)
		(fp_line
			(start -0.12065 0.3048)
			(end -0.67945 0.3048)
			(stroke
				(width 0.1)
				(type default)
			)
			(layer "F.Fab")
		)
		(fp_line
			(start -0.12065 0.2794)
			(end -0.12065 0.3048)
			(stroke
				(width 0.1)
				(type default)
			)
			(layer "F.Fab")
		)
		(fp_line
			(start -0.12065 -0.2794)
			(end 0.12065 -0.2794)
			(stroke
				(width 0.1)
				(type default)
			)
			(layer "F.Fab")
		)
		(fp_line
			(start -0.12065 -0.305054)
			(end -0.12065 -0.2794)
			(stroke
				(width 0.1)
				(type default)
			)
			(layer "F.Fab")
		)
		(fp_line
			(start -0.67945 0.3048)
			(end -0.67945 -0.305054)
			(stroke
				(width 0.1)
				(type default)
			)
			(layer "F.Fab")
		)
		(fp_line
			(start -0.67945 -0.305054)
			(end -0.12065 -0.305054)
			(stroke
				(width 0.1)
				(type default)
			)
			(layer "F.Fab")
		)
		(pad "1" smd circle
			(at -0.40005 0 180)
			(size 0 0)
			(layers "F.Cu" "F.Mask" "F.Paste")
			(net "SVID_CLK0_CPU1_R")
		)
		(pad "2" smd circle
			(at 0.40005 0 180)
			(size 0 0)
			(layers "F.Cu" "F.Mask" "F.Paste")
			(net "SVID_CLK_PVCCINFAON_CPU1_R")
		)
	)
	(footprint ""
		(layer "F.Cu")
		(at 430.600104 -139.574778)
		(property "Reference" "C3275"
			(at 0 0 0)
			(layer "F.SilkS")
			(hide yes)
			(effects
				(font
					(size 1.27 1.27)
				)
			)
		)
		(property "Value" ""
			(at 0 0 0)
			(layer "F.Fab")
			(effects
				(font
					(size 1.27 1.27)
				)
			)
		)
		(duplicate_pad_numbers_are_jumpers no)
		(fp_line
			(start -0.7874 -0.4064)
			(end 0.7874 -0.4064)
			(stroke
				(width 0.1524)
				(type default)
			)
			(layer "F.SilkS")
		)
		(fp_line
			(start -0.7874 0.4064)
			(end -0.7874 -0.4064)
			(stroke
				(width 0.1524)
				(type default)
			)
			(layer "F.SilkS")
		)
		(fp_line
			(start 0.7874 -0.4064)
			(end 0.7874 0.4064)
			(stroke
				(width 0.1524)
				(type default)
			)
			(layer "F.SilkS")
		)
		(fp_line
			(start 0.7874 0.4064)
			(end -0.7874 0.4064)
			(stroke
				(width 0.1524)
				(type default)
			)
			(layer "F.SilkS")
		)
		(fp_line
			(start -0.67945 -0.305054)
			(end -0.12065 -0.305054)
			(stroke
				(width 0.1)
				(type default)
			)
			(layer "F.Fab")
		)
		(fp_line
			(start -0.67945 0.3048)
			(end -0.67945 -0.305054)
			(stroke
				(width 0.1)
				(type default)
			)
			(layer "F.Fab")
		)
		(fp_line
			(start -0.12065 -0.305054)
			(end -0.12065 -0.2794)
			(stroke
				(width 0.1)
				(type default)
			)
			(layer "F.Fab")
		)
		(fp_line
			(start -0.12065 -0.2794)
			(end 0.12065 -0.2794)
			(stroke
				(width 0.1)
				(type default)
			)
			(layer "F.Fab")
		)
		(fp_line
			(start -0.12065 0.2794)
			(end -0.12065 0.3048)
			(stroke
				(width 0.1)
				(type default)
			)
			(layer "F.Fab")
		)
		(fp_line
			(start -0.12065 0.3048)
			(end -0.67945 0.3048)
			(stroke
				(width 0.1)
				(type default)
			)
			(layer "F.Fab")
		)
		(fp_line
			(start 0.120396 0.2794)
			(end -0.12065 0.2794)
			(stroke
				(width 0.1)
				(type default)
			)
			(layer "F.Fab")
		)
		(fp_line
			(start 0.120396 0.3048)
			(end 0.120396 0.2794)
			(stroke
				(width 0.1)
				(type default)
			)
			(layer "F.Fab")
		)
		(fp_line
			(start 0.12065 -0.3048)
			(end 0.67945 -0.3048)
			(stroke
				(width 0.1)
				(type default)
			)
			(layer "F.Fab")
		)
		(fp_line
			(start 0.12065 -0.2794)
			(end 0.12065 -0.3048)
			(stroke
				(width 0.1)
				(type default)
			)
			(layer "F.Fab")
		)
		(fp_line
			(start 0.67945 -0.3048)
			(end 0.67945 0.3048)
			(stroke
				(width 0.1)
				(type default)
			)
			(layer "F.Fab")
		)
		(fp_line
			(start 0.67945 0.3048)
			(end 0.120396 0.3048)
			(stroke
				(width 0.1)
				(type default)
			)
			(layer "F.Fab")
		)
		(pad "1" smd circle
			(at -0.40005 0)
			(size 0 0)
			(layers "F.Cu" "F.Mask" "F.Paste")
			(net "PVCCFA_EHV_CPU0_EN_R")
		)
		(pad "2" smd circle
			(at 0.40005 0)
			(size 0 0)
			(layers "F.Cu" "F.Mask" "F.Paste")
			(net "GND")
		)
	)
)
